(kicad_sch
	(version 20250114)
	(generator "eeschema")
	(generator_version "9.0")
	(paper "A3")
	(title_block
		(title "CM4 Baseboard")
		(date "2026-01-05")
		(rev "1.1.1")
		(company "Antmicro Ltd")
		(comment 1 "www.antmicro.com")
	)
	(bus_alias "CSI"
		(members "D0_P" "D0_N" "D1_P" "D1_N" "D2_P" "D2_N" "D3_P" "D3_N" "CLK_P"
			"CLK_N"
		)
	)
	(bus_alias "DSI"
		(members "D0_P" "D0_N" "D1_P" "D1_N" "D2_P" "D2_N" "D3_P" "D3_N" "CLK_P"
			"CLK_N"
		)
	)
	(bus_alias "Ethernet"
		(members "D0_P" "D0_N" "D1_P" "D1_N" "D2_P" "D2_N" "D3_P" "D3_N" "LED_ACT"
			"LED_LINK"
		)
	)
	(bus_alias "HDMI"
		(members "D0_P" "D0_N" "D1_P" "D1_N" "D2_P" "D2_N" "CLK_P" "CLK_N" "SCL"
			"SDA" "CEC" "HPD"
		)
	)
	(bus_alias "I_{2}C"
		(members "SCL" "SDA")
	)
	(bus_alias "PCIe"
		(members "TX0_P" "TX0_N" "RX0_P" "RX0_N" "CLK_P" "CLK_N" "TX1_N" "TX2_N"
			"TX3_N" "TX1_P" "TX2_P" "TX3_P" "RX1_N" "RX2_N" "RX3_N" "RX1_P" "RX2_P"
			"RX3_P" "~{RST}" "~{CLK_REQ}"
		)
	)
	(bus_alias "SDIO"
		(members "D0" "D1" "D2" "D3" "CMD" "CLK" "CD")
	)
	(bus_alias "UART"
		(members "TX" "RX")
	)
	(bus_alias "USB"
		(members "RX_P" "RX_N" "TX_P" "TX_N" "D_P" "D_N" "OTGID")
	)
	(junction
		(at 321.31 157.48)
		(diameter 0)
		(color 0 0 0 0)
	)
	(junction
		(at 321.31 185.42)
		(diameter 0)
		(color 0 0 0 0)
	)
	(junction
		(at 379.73 231.14)
		(diameter 0)
		(color 0 0 0 0)
	)
	(junction
		(at 379.73 224.79)
		(diameter 0)
		(color 0 0 0 0)
	)
	(junction
		(at 379.73 237.49)
		(diameter 0)
		(color 0 0 0 0)
	)
	(junction
		(at 245.11 200.66)
		(diameter 0)
		(color 0 0 0 0)
	)
	(bus
		(pts
			(xy 254 78.74) (xy 276.86 78.74)
		)
		(stroke
			(width 0)
			(type default)
		)
	)
	(bus
		(pts
			(xy 254 151.13) (xy 243.84 151.13)
		)
		(stroke
			(width 0)
			(type default)
		)
	)
	(wire
		(pts
			(xy 135.89 86.36) (xy 139.7 86.36)
		)
		(stroke
			(width 0)
			(type default)
		)
	)
	(bus
		(pts
			(xy 269.24 137.16) (xy 243.84 137.16)
		)
		(stroke
			(width 0)
			(type default)
		)
	)
	(bus
		(pts
			(xy 276.86 107.95) (xy 266.7 107.95)
		)
		(stroke
			(width 0)
			(type default)
		)
	)
	(wire
		(pts
			(xy 135.89 156.21) (xy 199.39 156.21)
		)
		(stroke
			(width 0)
			(type default)
		)
	)
	(wire
		(pts
			(xy 139.7 86.36) (xy 139.7 100.33)
		)
		(stroke
			(width 0)
			(type default)
		)
	)
	(bus
		(pts
			(xy 245.11 200.66) (xy 321.31 200.66)
		)
		(stroke
			(width 0)
			(type default)
		)
	)
	(bus
		(pts
			(xy 269.24 110.49) (xy 276.86 110.49)
		)
		(stroke
			(width 0)
			(type default)
		)
	)
	(bus
		(pts
			(xy 144.78 200.66) (xy 245.11 200.66)
		)
		(stroke
			(width 0)
			(type default)
		)
	)
	(bus
		(pts
			(xy 269.24 147.32) (xy 269.24 137.16)
		)
		(stroke
			(width 0)
			(type default)
		)
	)
	(bus
		(pts
			(xy 135.89 143.51) (xy 199.39 143.51)
		)
		(stroke
			(width 0)
			(type default)
		)
	)
	(bus
		(pts
			(xy 314.96 185.42) (xy 321.31 185.42)
		)
		(stroke
			(width 0)
			(type default)
		)
	)
	(bus
		(pts
			(xy 276.86 147.32) (xy 269.24 147.32)
		)
		(stroke
			(width 0)
			(type default)
		)
	)
	(bus
		(pts
			(xy 135.89 160.02) (xy 144.78 160.02)
		)
		(stroke
			(width 0)
			(type default)
		)
	)
	(bus
		(pts
			(xy 276.86 177.8) (xy 256.54 177.8)
		)
		(stroke
			(width 0)
			(type default)
		)
	)
	(bus
		(pts
			(xy 251.46 182.88) (xy 276.86 182.88)
		)
		(stroke
			(width 0)
			(type default)
		)
	)
	(wire
		(pts
			(xy 379.73 231.14) (xy 381 231.14)
		)
		(stroke
			(width 0)
			(type default)
		)
	)
	(bus
		(pts
			(xy 256.54 148.59) (xy 243.84 148.59)
		)
		(stroke
			(width 0)
			(type default)
		)
	)
	(bus
		(pts
			(xy 251.46 153.67) (xy 251.46 182.88)
		)
		(stroke
			(width 0)
			(type default)
		)
	)
	(bus
		(pts
			(xy 259.08 175.26) (xy 259.08 146.05)
		)
		(stroke
			(width 0)
			(type default)
		)
	)
	(wire
		(pts
			(xy 189.23 74.93) (xy 135.89 74.93)
		)
		(stroke
			(width 0)
			(type default)
		)
	)
	(bus
		(pts
			(xy 243.84 153.67) (xy 251.46 153.67)
		)
		(stroke
			(width 0)
			(type default)
		)
	)
	(wire
		(pts
			(xy 139.7 132.08) (xy 135.89 132.08)
		)
		(stroke
			(width 0)
			(type default)
		)
	)
	(bus
		(pts
			(xy 254 105.41) (xy 254 78.74)
		)
		(stroke
			(width 0)
			(type default)
		)
	)
	(wire
		(pts
			(xy 139.7 100.33) (xy 143.51 100.33)
		)
		(stroke
			(width 0)
			(type default)
		)
	)
	(bus
		(pts
			(xy 276.86 175.26) (xy 259.08 175.26)
		)
		(stroke
			(width 0)
			(type default)
		)
	)
	(wire
		(pts
			(xy 379.73 237.49) (xy 381 237.49)
		)
		(stroke
			(width 0)
			(type default)
		)
	)
	(bus
		(pts
			(xy 266.7 149.86) (xy 276.86 149.86)
		)
		(stroke
			(width 0)
			(type default)
		)
	)
	(bus
		(pts
			(xy 266.7 139.7) (xy 266.7 149.86)
		)
		(stroke
			(width 0)
			(type default)
		)
	)
	(bus
		(pts
			(xy 266.7 107.95) (xy 266.7 120.65)
		)
		(stroke
			(width 0)
			(type default)
		)
	)
	(bus
		(pts
			(xy 276.86 76.2) (xy 251.46 76.2)
		)
		(stroke
			(width 0)
			(type default)
		)
	)
	(bus
		(pts
			(xy 135.89 138.43) (xy 199.39 138.43)
		)
		(stroke
			(width 0)
			(type default)
		)
	)
	(wire
		(pts
			(xy 379.73 218.44) (xy 379.73 224.79)
		)
		(stroke
			(width 0)
			(type default)
		)
	)
	(bus
		(pts
			(xy 191.77 106.68) (xy 199.39 106.68)
		)
		(stroke
			(width 0)
			(type default)
		)
	)
	(bus
		(pts
			(xy 243.84 139.7) (xy 266.7 139.7)
		)
		(stroke
			(width 0)
			(type default)
		)
	)
	(bus
		(pts
			(xy 251.46 76.2) (xy 251.46 102.87)
		)
		(stroke
			(width 0)
			(type default)
		)
	)
	(bus
		(pts
			(xy 251.46 102.87) (xy 243.84 102.87)
		)
		(stroke
			(width 0)
			(type default)
		)
	)
	(wire
		(pts
			(xy 143.51 120.65) (xy 139.7 120.65)
		)
		(stroke
			(width 0)
			(type default)
		)
	)
	(bus
		(pts
			(xy 243.84 120.65) (xy 266.7 120.65)
		)
		(stroke
			(width 0)
			(type default)
		)
	)
	(bus
		(pts
			(xy 321.31 88.9) (xy 321.31 157.48)
		)
		(stroke
			(width 0)
			(type default)
		)
	)
	(bus
		(pts
			(xy 245.11 158.75) (xy 245.11 200.66)
		)
		(stroke
			(width 0)
			(type default)
		)
	)
	(bus
		(pts
			(xy 256.54 107.95) (xy 243.84 107.95)
		)
		(stroke
			(width 0)
			(type default)
		)
	)
	(bus
		(pts
			(xy 243.84 158.75) (xy 245.11 158.75)
		)
		(stroke
			(width 0)
			(type default)
		)
	)
	(bus
		(pts
			(xy 135.89 153.67) (xy 199.39 153.67)
		)
		(stroke
			(width 0)
			(type default)
		)
	)
	(bus
		(pts
			(xy 321.31 157.48) (xy 314.96 157.48)
		)
		(stroke
			(width 0)
			(type default)
		)
	)
	(bus
		(pts
			(xy 256.54 177.8) (xy 256.54 148.59)
		)
		(stroke
			(width 0)
			(type default)
		)
	)
	(bus
		(pts
			(xy 321.31 200.66) (xy 321.31 185.42)
		)
		(stroke
			(width 0)
			(type default)
		)
	)
	(wire
		(pts
			(xy 379.73 231.14) (xy 379.73 237.49)
		)
		(stroke
			(width 0)
			(type default)
		)
	)
	(bus
		(pts
			(xy 191.77 72.39) (xy 191.77 106.68)
		)
		(stroke
			(width 0)
			(type default)
		)
	)
	(bus
		(pts
			(xy 321.31 185.42) (xy 321.31 157.48)
		)
		(stroke
			(width 0)
			(type default)
		)
	)
	(wire
		(pts
			(xy 379.73 224.79) (xy 379.73 231.14)
		)
		(stroke
			(width 0)
			(type default)
		)
	)
	(wire
		(pts
			(xy 379.73 224.79) (xy 381 224.79)
		)
		(stroke
			(width 0)
			(type default)
		)
	)
	(bus
		(pts
			(xy 243.84 105.41) (xy 254 105.41)
		)
		(stroke
			(width 0)
			(type default)
		)
	)
	(bus
		(pts
			(xy 254 180.34) (xy 254 151.13)
		)
		(stroke
			(width 0)
			(type default)
		)
	)
	(wire
		(pts
			(xy 189.23 109.22) (xy 189.23 74.93)
		)
		(stroke
			(width 0)
			(type default)
		)
	)
	(bus
		(pts
			(xy 135.89 135.89) (xy 199.39 135.89)
		)
		(stroke
			(width 0)
			(type default)
		)
	)
	(bus
		(pts
			(xy 269.24 123.19) (xy 269.24 110.49)
		)
		(stroke
			(width 0)
			(type default)
		)
	)
	(wire
		(pts
			(xy 381 218.44) (xy 379.73 218.44)
		)
		(stroke
			(width 0)
			(type default)
		)
	)
	(bus
		(pts
			(xy 135.89 72.39) (xy 191.77 72.39)
		)
		(stroke
			(width 0)
			(type default)
		)
	)
	(bus
		(pts
			(xy 314.96 88.9) (xy 321.31 88.9)
		)
		(stroke
			(width 0)
			(type default)
		)
	)
	(wire
		(pts
			(xy 139.7 120.65) (xy 139.7 132.08)
		)
		(stroke
			(width 0)
			(type default)
		)
	)
	(wire
		(pts
			(xy 181.61 118.11) (xy 199.39 118.11)
		)
		(stroke
			(width 0)
			(type default)
		)
	)
	(bus
		(pts
			(xy 256.54 81.28) (xy 256.54 107.95)
		)
		(stroke
			(width 0)
			(type default)
		)
	)
	(bus
		(pts
			(xy 135.89 140.97) (xy 199.39 140.97)
		)
		(stroke
			(width 0)
			(type default)
		)
	)
	(bus
		(pts
			(xy 276.86 180.34) (xy 254 180.34)
		)
		(stroke
			(width 0)
			(type default)
		)
	)
	(bus
		(pts
			(xy 259.08 146.05) (xy 243.84 146.05)
		)
		(stroke
			(width 0)
			(type default)
		)
	)
	(bus
		(pts
			(xy 243.84 123.19) (xy 269.24 123.19)
		)
		(stroke
			(width 0)
			(type default)
		)
	)
	(bus
		(pts
			(xy 276.86 81.28) (xy 256.54 81.28)
		)
		(stroke
			(width 0)
			(type default)
		)
	)
	(wire
		(pts
			(xy 199.39 109.22) (xy 189.23 109.22)
		)
		(stroke
			(width 0)
			(type default)
		)
	)
	(wire
		(pts
			(xy 379.73 237.49) (xy 379.73 240.03)
		)
		(stroke
			(width 0)
			(type default)
		)
	)
	(bus
		(pts
			(xy 144.78 160.02) (xy 144.78 200.66)
		)
		(stroke
			(width 0)
			(type default)
		)
	)
	(symbol
		(lib_id "antmicropower:GND")
		(at 379.73 240.03 0)
		(unit 1)
		(exclude_from_sim no)
		(in_bom yes)
		(on_board yes)
		(dnp no)
		(fields_autoplaced yes)
		(property "Reference" "#PWR0101"
			(at 388.62 242.57 0)
			(effects
				(font
					(size 1.27 1.27)
					(thickness 0.15)
				)
				(justify left bottom)
				(hide yes)
			)
		)
		(property "Value" "GND"
			(at 379.73 245.11 0)
			(effects
				(font
					(size 1.27 1.27)
					(thickness 0.15)
				)
			)
		)
		(property "Footprint" ""
			(at 388.62 247.65 0)
			(effects
				(font
					(size 1.27 1.27)
					(thickness 0.15)
				)
				(justify left bottom)
				(hide yes)
			)
		)
		(property "Datasheet" ""
			(at 388.62 252.73 0)
			(effects
				(font
					(size 1.27 1.27)
					(thickness 0.15)
				)
				(justify left bottom)
				(hide yes)
			)
		)
		(property "Description" ""
			(at 379.73 240.03 0)
			(effects
				(font
					(size 1.27 1.27)
				)
				(hide yes)
			)
		)
		(property "Author" "Antmicro"
			(at 388.62 247.65 0)
			(effects
				(font
					(size 1.27 1.27)
					(thickness 0.15)
				)
				(justify left bottom)
				(hide yes)
			)
		)
		(property "License" "Apache-2.0"
			(at 388.62 250.19 0)
			(effects
				(font
					(size 1.27 1.27)
					(thickness 0.15)
				)
				(justify left bottom)
				(hide yes)
			)
		)
		(pin "1"
		)
		(instances
			(project "cm4-baseboard"
				(path ""
					(reference "#PWR0101")
					(unit 1)
				)
			)
		)
	)
	(symbol
		(lib_id "antmicroMechanicalParts:Spacer_Drill3.7mm_H6mm_9774060151R")
		(at 381 224.79 0)
		(unit 1)
		(exclude_from_sim no)
		(in_bom yes)
		(on_board yes)
		(dnp no)
		(property "Reference" "H102"
			(at 389.89 223.52 0)
			(effects
				(font
					(size 1.27 1.27)
				)
				(justify left)
			)
		)
		(property "Value" "Spacer_Drill3.7mm_H6mm_9774060151R"
			(at 389.89 224.7899 0)
			(effects
				(font
					(size 1.27 1.27)
				)
				(justify left)
				(hide yes)
			)
		)
		(property "Footprint" "antmicro-footprints:Spacer_Drill3.7mm_H6mm_9774060151R"
			(at 403.86 232.41 0)
			(effects
				(font
					(size 1.27 1.27)
					(thickness 0.15)
				)
				(justify left bottom)
				(hide yes)
			)
		)
		(property "Datasheet" "https://www.we-online.com/components/products/datasheet/9774060151R.pdf"
			(at 403.86 234.95 0)
			(effects
				(font
					(size 1.27 1.27)
					(thickness 0.15)
				)
				(justify left bottom)
				(hide yes)
			)
		)
		(property "Description" ""
			(at 381 224.79 0)
			(effects
				(font
					(size 1.27 1.27)
				)
				(hide yes)
			)
		)
		(property "Manufacturer" "Würth Elektronik"
			(at 403.86 237.49 0)
			(effects
				(font
					(size 1.27 1.27)
					(thickness 0.15)
				)
				(justify left bottom)
				(hide yes)
			)
		)
		(property "MPN" "9774060151R"
			(at 389.89 226.0601 0)
			(effects
				(font
					(size 1.27 1.27)
					(thickness 0.15)
				)
				(justify left)
			)
		)
		(property "Author" "Antmicro"
			(at 403.86 242.57 0)
			(effects
				(font
					(size 1.27 1.27)
					(thickness 0.15)
				)
				(justify left bottom)
				(hide yes)
			)
		)
		(property "License" "Apache-2.0"
			(at 403.86 245.11 0)
			(effects
				(font
					(size 1.27 1.27)
					(thickness 0.15)
				)
				(justify left bottom)
				(hide yes)
			)
		)
		(pin "1"
		)
		(instances
			(project "cm4-baseboard"
				(path ""
					(reference "H102")
					(unit 1)
				)
			)
		)
	)
	(symbol
		(lib_id "antmicroMechanicalParts:Spacer_Drill3.7mm_H6mm_9774060151R")
		(at 381 218.44 0)
		(unit 1)
		(exclude_from_sim no)
		(in_bom yes)
		(on_board yes)
		(dnp no)
		(property "Reference" "H101"
			(at 389.89 217.17 0)
			(effects
				(font
					(size 1.27 1.27)
				)
				(justify left)
			)
		)
		(property "Value" "Spacer_Drill3.7mm_H6mm_9774060151R"
			(at 389.89 218.4399 0)
			(effects
				(font
					(size 1.27 1.27)
				)
				(justify left)
				(hide yes)
			)
		)
		(property "Footprint" "antmicro-footprints:Spacer_Drill3.7mm_H6mm_9774060151R"
			(at 403.86 226.06 0)
			(effects
				(font
					(size 1.27 1.27)
					(thickness 0.15)
				)
				(justify left bottom)
				(hide yes)
			)
		)
		(property "Datasheet" "https://www.we-online.com/components/products/datasheet/9774060151R.pdf"
			(at 403.86 228.6 0)
			(effects
				(font
					(size 1.27 1.27)
					(thickness 0.15)
				)
				(justify left bottom)
				(hide yes)
			)
		)
		(property "Description" ""
			(at 381 218.44 0)
			(effects
				(font
					(size 1.27 1.27)
				)
				(hide yes)
			)
		)
		(property "Manufacturer" "Würth Elektronik"
			(at 403.86 231.14 0)
			(effects
				(font
					(size 1.27 1.27)
					(thickness 0.15)
				)
				(justify left bottom)
				(hide yes)
			)
		)
		(property "MPN" "9774060151R"
			(at 389.89 219.7101 0)
			(effects
				(font
					(size 1.27 1.27)
					(thickness 0.15)
				)
				(justify left)
			)
		)
		(property "Author" "Antmicro"
			(at 403.86 236.22 0)
			(effects
				(font
					(size 1.27 1.27)
					(thickness 0.15)
				)
				(justify left bottom)
				(hide yes)
			)
		)
		(property "License" "Apache-2.0"
			(at 403.86 238.76 0)
			(effects
				(font
					(size 1.27 1.27)
					(thickness 0.15)
				)
				(justify left bottom)
				(hide yes)
			)
		)
		(pin "1"
		)
		(instances
			(project "cm4-baseboard"
				(path ""
					(reference "H101")
					(unit 1)
				)
			)
		)
	)
	(symbol
		(lib_id "antmicroMechanicalParts:Spacer_Drill3.7mm_H6mm_9774060151R")
		(at 381 237.49 0)
		(unit 1)
		(exclude_from_sim no)
		(in_bom yes)
		(on_board yes)
		(dnp no)
		(property "Reference" "H104"
			(at 389.89 236.22 0)
			(effects
				(font
					(size 1.27 1.27)
				)
				(justify left)
			)
		)
		(property "Value" "Spacer_Drill3.7mm_H6mm_9774060151R"
			(at 389.89 237.4899 0)
			(effects
				(font
					(size 1.27 1.27)
				)
				(justify left)
				(hide yes)
			)
		)
		(property "Footprint" "antmicro-footprints:Spacer_Drill3.7mm_H6mm_9774060151R"
			(at 403.86 245.11 0)
			(effects
				(font
					(size 1.27 1.27)
					(thickness 0.15)
				)
				(justify left bottom)
				(hide yes)
			)
		)
		(property "Datasheet" "https://www.we-online.com/components/products/datasheet/9774060151R.pdf"
			(at 403.86 247.65 0)
			(effects
				(font
					(size 1.27 1.27)
					(thickness 0.15)
				)
				(justify left bottom)
				(hide yes)
			)
		)
		(property "Description" ""
			(at 381 237.49 0)
			(effects
				(font
					(size 1.27 1.27)
				)
				(hide yes)
			)
		)
		(property "Manufacturer" "Würth Elektronik"
			(at 403.86 250.19 0)
			(effects
				(font
					(size 1.27 1.27)
					(thickness 0.15)
				)
				(justify left bottom)
				(hide yes)
			)
		)
		(property "MPN" "9774060151R"
			(at 389.89 238.7601 0)
			(effects
				(font
					(size 1.27 1.27)
					(thickness 0.15)
				)
				(justify left)
			)
		)
		(property "Author" "Antmicro"
			(at 403.86 255.27 0)
			(effects
				(font
					(size 1.27 1.27)
					(thickness 0.15)
				)
				(justify left bottom)
				(hide yes)
			)
		)
		(property "License" "Apache-2.0"
			(at 403.86 257.81 0)
			(effects
				(font
					(size 1.27 1.27)
					(thickness 0.15)
				)
				(justify left bottom)
				(hide yes)
			)
		)
		(pin "1"
		)
		(instances
			(project "cm4-baseboard"
				(path ""
					(reference "H104")
					(unit 1)
				)
			)
		)
	)
	(symbol
		(lib_id "antmicroMechanicalParts:Spacer_Drill3.7mm_H6mm_9774060151R")
		(at 381 231.14 0)
		(unit 1)
		(exclude_from_sim no)
		(in_bom yes)
		(on_board yes)
		(dnp no)
		(property "Reference" "H103"
			(at 389.89 229.87 0)
			(effects
				(font
					(size 1.27 1.27)
				)
				(justify left)
			)
		)
		(property "Value" "Spacer_Drill3.7mm_H6mm_9774060151R"
			(at 389.89 231.1399 0)
			(effects
				(font
					(size 1.27 1.27)
				)
				(justify left)
				(hide yes)
			)
		)
		(property "Footprint" "antmicro-footprints:Spacer_Drill3.7mm_H6mm_9774060151R"
			(at 403.86 238.76 0)
			(effects
				(font
					(size 1.27 1.27)
					(thickness 0.15)
				)
				(justify left bottom)
				(hide yes)
			)
		)
		(property "Datasheet" "https://www.we-online.com/components/products/datasheet/9774060151R.pdf"
			(at 403.86 241.3 0)
			(effects
				(font
					(size 1.27 1.27)
					(thickness 0.15)
				)
				(justify left bottom)
				(hide yes)
			)
		)
		(property "Description" ""
			(at 381 231.14 0)
			(effects
				(font
					(size 1.27 1.27)
				)
				(hide yes)
			)
		)
		(property "Manufacturer" "Würth Elektronik"
			(at 403.86 243.84 0)
			(effects
				(font
					(size 1.27 1.27)
					(thickness 0.15)
				)
				(justify left bottom)
				(hide yes)
			)
		)
		(property "MPN" "9774060151R"
			(at 389.89 232.4101 0)
			(effects
				(font
					(size 1.27 1.27)
					(thickness 0.15)
				)
				(justify left)
			)
		)
		(property "Author" "Antmicro"
			(at 403.86 248.92 0)
			(effects
				(font
					(size 1.27 1.27)
					(thickness 0.15)
				)
				(justify left bottom)
				(hide yes)
			)
		)
		(property "License" "Apache-2.0"
			(at 403.86 251.46 0)
			(effects
				(font
					(size 1.27 1.27)
					(thickness 0.15)
				)
				(justify left bottom)
				(hide yes)
			)
		)
		(pin "1"
		)
		(instances
			(project "cm4-baseboard"
				(path ""
					(reference "H103")
					(unit 1)
				)
			)
		)
	)
	(sheet
		(at 199.39 101.6)
		(size 44.45 59.69)
		(exclude_from_sim no)
		(in_bom yes)
		(on_board yes)
		(dnp no)
		(fields_autoplaced yes)
		(stroke
			(width 0)
			(type solid)
		)
		(fill
			(color 0 0 0 0.0000)
		)
		(property "Sheetname" "Compute module"
			(at 199.39 100.8884 0)
			(effects
				(font
					(size 1.27 1.27)
				)
				(justify left bottom)
			)
		)
		(property "Sheetfile" "compute-module.kicad_sch"
			(at 199.39 161.8746 0)
			(effects
				(font
					(size 1.27 1.27)
				)
				(justify left top)
			)
		)
		(pin "ETHERNET{Ethernet}" bidirectional
			(at 199.39 106.68 180)
			(effects
				(font
					(size 1.27 1.27)
				)
				(justify left)
			)
		)
		(pin "HDMI{HDMI}" bidirectional
			(at 243.84 102.87 0)
			(effects
				(font
					(size 1.27 1.27)
				)
				(justify right)
			)
		)
		(pin "DSI{DSI}" output
			(at 243.84 105.41 0)
			(effects
				(font
					(size 1.27 1.27)
				)
				(justify right)
			)
		)
		(pin "UART.1{UART}" bidirectional
			(at 199.39 138.43 180)
			(effects
				(font
					(size 1.27 1.27)
				)
				(justify left)
			)
		)
		(pin "UART.2{UART}" bidirectional
			(at 199.39 140.97 180)
			(effects
				(font
					(size 1.27 1.27)
				)
				(justify left)
			)
		)
		(pin "NVMe{PCIe}" bidirectional
			(at 243.84 120.65 0)
			(effects
				(font
					(size 1.27 1.27)
				)
				(justify right)
			)
		)
		(pin "UART.3{UART}" bidirectional
			(at 199.39 143.51 180)
			(effects
				(font
					(size 1.27 1.27)
				)
				(justify left)
			)
		)
		(pin "SDIO{SDIO}" bidirectional
			(at 243.84 123.19 0)
			(effects
				(font
					(size 1.27 1.27)
				)
				(justify right)
			)
		)
		(pin "CSI0{CSI}" bidirectional
			(at 243.84 146.05 0)
			(effects
				(font
					(size 1.27 1.27)
				)
				(justify right)
			)
		)
		(pin "CSI1{CSI}" bidirectional
			(at 243.84 148.59 0)
			(effects
				(font
					(size 1.27 1.27)
				)
				(justify right)
			)
		)
		(pin "USB{USB}" bidirectional
			(at 199.39 153.67 180)
			(effects
				(font
					(size 1.27 1.27)
				)
				(justify left)
			)
		)
		(pin "UART.0{UART}" bidirectional
			(at 199.39 135.89 180)
			(effects
				(font
					(size 1.27 1.27)
				)
				(justify left)
			)
		)
		(pin "I_{2}C_CSI0{I_{2}C}" bidirectional
			(at 243.84 151.13 0)
			(effects
				(font
					(size 1.27 1.27)
				)
				(justify right)
			)
		)
		(pin "DSICtrl{DSICtrl}" bidirectional
			(at 243.84 107.95 0)
			(effects
				(font
					(size 1.27 1.27)
				)
				(justify right)
			)
		)
		(pin "NFC{NFC}" bidirectional
			(at 243.84 137.16 0)
			(effects
				(font
					(size 1.27 1.27)
				)
				(justify right)
			)
		)
		(pin "CamCtrl{CamCtrl}" output
			(at 243.84 153.67 0)
			(effects
				(font
					(size 1.27 1.27)
				)
				(justify right)
			)
		)
		(pin "NFC{NFC}" bidirectional
			(at 243.84 137.16 0)
			(effects
				(font
					(size 1.27 1.27)
				)
				(justify right)
			)
		)
		(pin "GPIO{GPIO}" bidirectional
			(at 243.84 139.7 0)
			(effects
				(font
					(size 1.27 1.27)
				)
				(justify right)
			)
		)
		(pin "~{POE EN}" output
			(at 199.39 109.22 180)
			(effects
				(font
					(size 1.27 1.27)
				)
				(justify left)
			)
		)
		(pin "NVMe_EN" output
			(at 199.39 118.11 180)
			(effects
				(font
					(size 1.27 1.27)
				)
				(justify left)
			)
		)
		(pin "USBA_VBUS" input
			(at 199.39 156.21 180)
			(effects
				(font
					(size 1.27 1.27)
				)
				(justify left)
			)
		)
		(pin "I_{2}C1{I_{2}C}" bidirectional
			(at 243.84 158.75 0)
			(effects
				(font
					(size 1.27 1.27)
				)
				(justify right)
			)
		)
		(instances
			(project "cm4-baseboard"
				(path ""
					(page "2")
				)
			)
		)
	)
	(sheet
		(at 97.79 63.5)
		(size 38.1 25.4)
		(exclude_from_sim no)
		(in_bom yes)
		(on_board yes)
		(dnp no)
		(fields_autoplaced yes)
		(stroke
			(width 0)
			(type solid)
		)
		(fill
			(color 0 0 0 0.0000)
		)
		(property "Sheetname" "Ethernet"
			(at 97.79 62.7884 0)
			(effects
				(font
					(size 1.27 1.27)
				)
				(justify left bottom)
			)
		)
		(property "Sheetfile" "ethernet.kicad_sch"
			(at 97.79 89.4846 0)
			(effects
				(font
					(size 1.27 1.27)
				)
				(justify left top)
			)
		)
		(pin "ETHERNET{Ethernet}" bidirectional
			(at 135.89 72.39 0)
			(effects
				(font
					(size 1.27 1.27)
				)
				(justify right)
			)
		)
		(pin "~{POE EN}" input
			(at 135.89 74.93 0)
			(effects
				(font
					(size 1.27 1.27)
				)
				(justify right)
			)
		)
		(pin "POE_12V" output
			(at 135.89 86.36 0)
			(effects
				(font
					(size 1.27 1.27)
				)
				(justify right)
			)
		)
		(instances
			(project "cm4-baseboard"
				(path ""
					(page "4")
				)
			)
		)
	)
	(sheet
		(at 143.51 97.79)
		(size 38.1 25.4)
		(exclude_from_sim no)
		(in_bom yes)
		(on_board yes)
		(dnp no)
		(fields_autoplaced yes)
		(stroke
			(width 0)
			(type solid)
		)
		(fill
			(color 0 0 0 0.0000)
		)
		(property "Sheetname" "Supply"
			(at 143.51 97.0784 0)
			(effects
				(font
					(size 1.27 1.27)
				)
				(justify left bottom)
			)
		)
		(property "Sheetfile" "supply.kicad_sch"
			(at 143.51 123.7746 0)
			(effects
				(font
					(size 1.27 1.27)
				)
				(justify left top)
			)
		)
		(pin "POE_12V" input
			(at 143.51 100.33 180)
			(effects
				(font
					(size 1.27 1.27)
				)
				(justify left)
			)
		)
		(pin "NVMe_EN" input
			(at 181.61 118.11 0)
			(effects
				(font
					(size 1.27 1.27)
				)
				(justify right)
			)
		)
		(pin "V_{BUS}" input
			(at 143.51 120.65 180)
			(effects
				(font
					(size 1.27 1.27)
				)
				(justify left)
			)
		)
		(instances
			(project "cm4-baseboard"
				(path ""
					(page "3")
				)
			)
		)
	)
	(sheet
		(at 276.86 100.33)
		(size 38.1 25.4)
		(exclude_from_sim no)
		(in_bom yes)
		(on_board yes)
		(dnp no)
		(fields_autoplaced yes)
		(stroke
			(width 0)
			(type solid)
		)
		(fill
			(color 0 0 0 0.0000)
		)
		(property "Sheetname" "NVMe & microSD"
			(at 276.86 99.6184 0)
			(effects
				(font
					(size 1.27 1.27)
				)
				(justify left bottom)
			)
		)
		(property "Sheetfile" "nvme-micro-sd.kicad_sch"
			(at 276.86 126.3146 0)
			(effects
				(font
					(size 1.27 1.27)
				)
				(justify left top)
			)
		)
		(pin "NVMe{PCIe}" bidirectional
			(at 276.86 107.95 180)
			(effects
				(font
					(size 1.27 1.27)
				)
				(justify left)
			)
		)
		(pin "SDIO{SDIO}" bidirectional
			(at 276.86 110.49 180)
			(effects
				(font
					(size 1.27 1.27)
				)
				(justify left)
			)
		)
		(instances
			(project "cm4-baseboard"
				(path ""
					(page "5")
				)
			)
		)
	)
	(sheet
		(at 276.86 167.64)
		(size 38.1 25.4)
		(exclude_from_sim no)
		(in_bom yes)
		(on_board yes)
		(dnp no)
		(fields_autoplaced yes)
		(stroke
			(width 0.1524)
			(type solid)
		)
		(fill
			(color 0 0 0 0.0000)
		)
		(property "Sheetname" "CSI"
			(at 276.86 166.9284 0)
			(effects
				(font
					(size 1.27 1.27)
				)
				(justify left bottom)
			)
		)
		(property "Sheetfile" "csi.kicad_sch"
			(at 276.86 193.6246 0)
			(effects
				(font
					(size 1.27 1.27)
				)
				(justify left top)
			)
		)
		(pin "CSI1{CSI}" bidirectional
			(at 276.86 177.8 180)
			(effects
				(font
					(size 1.27 1.27)
				)
				(justify left)
			)
		)
		(pin "CSI0{CSI}" bidirectional
			(at 276.86 175.26 180)
			(effects
				(font
					(size 1.27 1.27)
				)
				(justify left)
			)
		)
		(pin "I_{2}C_CSI0{I_{2}C}" bidirectional
			(at 276.86 180.34 180)
			(effects
				(font
					(size 1.27 1.27)
				)
				(justify left)
			)
		)
		(pin "CamCtrl{CamCtrl}" input
			(at 276.86 182.88 180)
			(effects
				(font
					(size 1.27 1.27)
				)
				(justify left)
			)
		)
		(pin "I_{2}C1{I_{2}C}" bidirectional
			(at 314.96 185.42 0)
			(effects
				(font
					(size 1.27 1.27)
				)
				(justify right)
			)
		)
		(instances
			(project "cm4-baseboard"
				(path ""
					(page "6")
				)
			)
		)
	)
	(sheet
		(at 97.79 130.81)
		(size 38.1 30.48)
		(exclude_from_sim no)
		(in_bom yes)
		(on_board yes)
		(dnp no)
		(fields_autoplaced yes)
		(stroke
			(width 0.1524)
			(type solid)
		)
		(fill
			(color 0 0 0 0.0000)
		)
		(property "Sheetname" "USB"
			(at 97.79 130.0984 0)
			(effects
				(font
					(size 1.27 1.27)
				)
				(justify left bottom)
			)
		)
		(property "Sheetfile" "usb.kicad_sch"
			(at 97.79 161.8746 0)
			(effects
				(font
					(size 1.27 1.27)
				)
				(justify left top)
			)
		)
		(pin "UART.1{UART}" bidirectional
			(at 135.89 138.43 0)
			(effects
				(font
					(size 1.27 1.27)
				)
				(justify right)
			)
		)
		(pin "UART.0{UART}" bidirectional
			(at 135.89 135.89 0)
			(effects
				(font
					(size 1.27 1.27)
				)
				(justify right)
			)
		)
		(pin "UART.2{UART}" bidirectional
			(at 135.89 140.97 0)
			(effects
				(font
					(size 1.27 1.27)
				)
				(justify right)
			)
		)
		(pin "UART.3{UART}" bidirectional
			(at 135.89 143.51 0)
			(effects
				(font
					(size 1.27 1.27)
				)
				(justify right)
			)
		)
		(pin "V_{BUS}" output
			(at 135.89 132.08 0)
			(effects
				(font
					(size 1.27 1.27)
				)
				(justify right)
			)
		)
		(pin "USBA{USB}" bidirectional
			(at 135.89 153.67 0)
			(effects
				(font
					(size 1.27 1.27)
				)
				(justify right)
			)
		)
		(pin "USBA_VBUS" output
			(at 135.89 156.21 0)
			(effects
				(font
					(size 1.27 1.27)
				)
				(justify right)
			)
		)
		(pin "I_{2}C1{I_{2}C}" bidirectional
			(at 135.89 160.02 0)
			(effects
				(font
					(size 1.27 1.27)
				)
				(justify right)
			)
		)
		(instances
			(project "cm4-baseboard"
				(path ""
					(page "9")
				)
			)
		)
	)
	(sheet
		(at 276.86 66.04)
		(size 38.1 25.4)
		(exclude_from_sim no)
		(in_bom yes)
		(on_board yes)
		(dnp no)
		(fields_autoplaced yes)
		(stroke
			(width 0.1524)
			(type solid)
		)
		(fill
			(color 0 0 0 0.0000)
		)
		(property "Sheetname" "Display"
			(at 276.86 65.3284 0)
			(effects
				(font
					(size 1.27 1.27)
				)
				(justify left bottom)
			)
		)
		(property "Sheetfile" "display.kicad_sch"
			(at 276.86 92.0246 0)
			(effects
				(font
					(size 1.27 1.27)
				)
				(justify left top)
			)
		)
		(pin "DSI{DSI}" input
			(at 276.86 78.74 180)
			(effects
				(font
					(size 1.27 1.27)
				)
				(justify left)
			)
		)
		(pin "HDMI{HDMI}" bidirectional
			(at 276.86 76.2 180)
			(effects
				(font
					(size 1.27 1.27)
				)
				(justify left)
			)
		)
		(pin "DSICtrl{DSICtrl}" bidirectional
			(at 276.86 81.28 180)
			(effects
				(font
					(size 1.27 1.27)
				)
				(justify left)
			)
		)
		(pin "I_{2}C1{I_{2}C}" bidirectional
			(at 314.96 88.9 0)
			(effects
				(font
					(size 1.27 1.27)
				)
				(justify right)
			)
		)
		(instances
			(project "cm4-baseboard"
				(path ""
					(page "7")
				)
			)
		)
	)
	(sheet
		(at 276.86 134.62)
		(size 38.1 25.4)
		(exclude_from_sim no)
		(in_bom yes)
		(on_board yes)
		(dnp no)
		(fields_autoplaced yes)
		(stroke
			(width 0.1524)
			(type solid)
		)
		(fill
			(color 0 0 0 0.0000)
		)
		(property "Sheetname" "Peripherals"
			(at 276.86 133.9084 0)
			(effects
				(font
					(size 1.27 1.27)
				)
				(justify left bottom)
			)
		)
		(property "Sheetfile" "peripherals.kicad_sch"
			(at 276.86 160.6046 0)
			(effects
				(font
					(size 1.27 1.27)
				)
				(justify left top)
			)
		)
		(pin "NFC{NFC}" bidirectional
			(at 276.86 147.32 180)
			(effects
				(font
					(size 1.27 1.27)
				)
				(justify left)
			)
		)
		(pin "GPIO{GPIO}" bidirectional
			(at 276.86 149.86 180)
			(effects
				(font
					(size 1.27 1.27)
				)
				(justify left)
			)
		)
		(pin "I_{2}C1{I_{2}C}" bidirectional
			(at 314.96 157.48 0)
			(effects
				(font
					(size 1.27 1.27)
				)
				(justify right)
			)
		)
		(instances
			(project "cm4-baseboard"
				(path ""
					(page "8")
				)
			)
		)
	)
	(sheet_instances
		(path "/"
			(page "1")
		)
	)
)
